(kicad_pcb
	(version 20260206)
	(generator "pcbnew")
	(generator_version "10.0")
	(general
		(thickness 1.6)
		(legacy_teardrops no)
	)
	(paper "A4")
	(title_block
		(title "netronome-mezz — pcbd0082-001_rev01_jul9_a.brd")
		(comment 1 "Open CloudServer (Microsoft) / footprints 66-73 of 714")
	)
	(layers
		(0 "F.Cu" signal "TOP")
		(4 "In1.Cu" signal "02_GND")
		(6 "In2.Cu" signal "03_SIG")
		(8 "In3.Cu" signal "04_SIG")
		(10 "In4.Cu" signal "05_GND")
		(12 "In5.Cu" signal "06_PWR1")
		(14 "In6.Cu" signal "07_SIG")
		(16 "In7.Cu" signal "08_SIG")
		(18 "In8.Cu" signal "09_GND")
		(2 "B.Cu" signal "BOTTOM")
		(9 "F.Adhes" user "F.Adhesive")
		(11 "B.Adhes" user "B.Adhesive")
		(13 "F.Paste" user "Package Geometry/Pastemask Top")
		(15 "B.Paste" user "Package Geometry/Pastemask Bottom")
		(5 "F.SilkS" user "Ref Des/Silkscreen Top")
		(7 "B.SilkS" user "Ref Des/Silkscreen Bottom")
		(1 "F.Mask" user "Board Geometry/Soldermask Top")
		(3 "B.Mask" user "Board Geometry/Soldermask Bottom")
		(17 "Dwgs.User" user "User.Drawings")
		(19 "Cmts.User" user "User.Comments")
		(21 "Eco1.User" user "User.Eco1")
		(23 "Eco2.User" user "User.Eco2")
		(25 "Edge.Cuts" user "Board Geometry/Outline")
		(27 "Margin" user)
		(31 "F.CrtYd" user "Package Geometry/Place Bound Top")
		(29 "B.CrtYd" user "Package Geometry/Place Bound Bottom")
		(35 "F.Fab" user "Ref Des/Assembly Top")
		(33 "B.Fab" user "Ref Des/Assembly Bottom")
		(45 "User.4" user "COMPVAL_TYPE_BOTTOM")
	)
	(footprint ""
		(layer "F.Cu")
		(at 53.086 46.99 -90)
		(property "Reference" "C62"
			(at 1.29667 -0.254 0)
			(unlocked yes)
			(layer "F.SilkS")
			(effects
				(font
					(size 0.7874 0.5842)
					(thickness 0.127)
				)
				(justify left)
			)
		)
		(property "Value" "100UF"
			(at -0.78232 0.4826 0)
			(unlocked yes)
			(layer "F.Fab")
			(hide yes)
			(effects
				(font
					(size 1.27 0.9652)
					(thickness 0.000001)
				)
				(justify left)
			)
		)
		(property "Device Type" "CAPC0087"
			(at -0.78232 0.4826 0)
			(unlocked yes)
			(layer "F.Fab")
			(hide yes)
			(effects
				(font
					(size 1.27 0.9652)
					(thickness 0.000001)
				)
				(justify left)
			)
		)
		(duplicate_pad_numbers_are_jumpers no)
		(fp_circle
			(center 0 0)
			(end 0 -0.508)
			(stroke
				(width 0.2032)
				(type default)
			)
			(fill no)
			(layer "F.SilkS")
		)
		(fp_circle
			(center 0 0)
			(end 0 -0.508)
			(stroke
				(width 0.2032)
				(type default)
			)
			(fill no)
			(layer "F.SilkS")
		)
		(fp_poly
			(pts
				(xy -1.27 2.9464) (xy 1.27 2.9464) (xy 1.27 -2.9464) (xy -1.27 -2.9464)
			)
			(stroke
				(width 0)
				(type default)
			)
			(fill no)
			(layer "F.CrtYd")
		)
		(fp_line
			(start -1.016 2.794)
			(end -1.016 -2.794)
			(stroke
				(width 0.0254)
				(type default)
			)
			(layer "F.Fab")
		)
		(fp_line
			(start 1.016 2.794)
			(end -1.016 2.794)
			(stroke
				(width 0.0254)
				(type default)
			)
			(layer "F.Fab")
		)
		(fp_line
			(start -1.016 -2.794)
			(end 1.016 -2.794)
			(stroke
				(width 0.0254)
				(type default)
			)
			(layer "F.Fab")
		)
		(fp_line
			(start 1.016 -2.794)
			(end 1.016 2.794)
			(stroke
				(width 0.0254)
				(type default)
			)
			(layer "F.Fab")
		)
		(pad "1" smd rect
			(at 0 -1.6764 270)
			(size 1.524 1.524)
			(layers "F.Cu" "F.Mask" "F.Paste")
			(net "VDD_CORE")
		)
		(pad "2" smd rect
			(at 0 1.6764 270)
			(size 1.524 1.524)
			(layers "F.Cu" "F.Mask" "F.Paste")
			(net "GND")
		)
		(zone
			(layer "F.Cu")
			(hatch none 0.5)
			(connect_pads
				(clearance 0)
			)
			(min_thickness 0.25)
			(keepout
				(tracks allowed)
				(vias not_allowed)
				(pads allowed)
				(copperpour not_allowed)
				(footprints allowed)
			)
			(placement
				(enabled no)
				(sheetname "")
			)
			(fill
				(thermal_gap 0.5)
				(thermal_bridge_width 0.5)
				(island_removal_mode 0)
			)
			(polygon
				(pts
					(xy 51.4858 46.2026) (xy 51.4858 47.7774) (xy 54.6862 47.7774) (xy 54.6862 46.2026)
				)
			)
		)
		(zone
			(layer "F.Cu")
			(hatch none 0.5)
			(connect_pads
				(clearance 0)
			)
			(min_thickness 0.25)
			(keepout
				(tracks not_allowed)
				(vias allowed)
				(pads allowed)
				(copperpour not_allowed)
				(footprints allowed)
			)
			(placement
				(enabled no)
				(sheetname "")
			)
			(fill
				(thermal_gap 0.5)
				(thermal_bridge_width 0.5)
				(island_removal_mode 0)
			)
			(polygon
				(pts
					(xy 52.3494 46.2026) (xy 52.3494 47.7774) (xy 52.197 47.7774) (xy 52.197 46.2026)
				)
			)
		)
		(zone
			(layer "F.Cu")
			(hatch none 0.5)
			(connect_pads
				(clearance 0)
			)
			(min_thickness 0.25)
			(keepout
				(tracks not_allowed)
				(vias allowed)
				(pads allowed)
				(copperpour not_allowed)
				(footprints allowed)
			)
			(placement
				(enabled no)
				(sheetname "")
			)
			(fill
				(thermal_gap 0.5)
				(thermal_bridge_width 0.5)
				(island_removal_mode 0)
			)
			(polygon
				(pts
					(xy 53.975 46.2026) (xy 53.975 47.7774) (xy 53.8226 47.7774) (xy 53.8226 46.2026)
				)
			)
		)
	)
	(footprint ""
		(layer "F.Cu")
		(at 7.112 40.64)
		(property "Reference" "TP23"
			(at -0.48133 4.064 90)
			(unlocked yes)
			(layer "F.SilkS")
			(effects
				(font
					(size 0.7874 0.5842)
					(thickness 0.127)
				)
				(justify left)
			)
		)
		(property "Value" "*"
			(at -0.4826 -0.14732 0)
			(unlocked yes)
			(layer "F.Fab")
			(hide yes)
			(effects
				(font
					(size 1.27 0.9652)
					(thickness 0.000001)
				)
				(justify left)
			)
		)
		(property "Device Type" "TP_SMALL"
			(at -0.4826 -0.14732 0)
			(unlocked yes)
			(layer "F.Fab")
			(hide yes)
			(effects
				(font
					(size 1.27 0.9652)
					(thickness 0.000001)
				)
				(justify left)
			)
		)
		(duplicate_pad_numbers_are_jumpers no)
		(fp_line
			(start -0.8636 -0.8636)
			(end -0.8636 0.8636)
			(stroke
				(width 0.1524)
				(type default)
			)
			(layer "F.SilkS")
		)
		(fp_line
			(start -0.8636 0.8636)
			(end 0.8636 0.8636)
			(stroke
				(width 0.1524)
				(type default)
			)
			(layer "F.SilkS")
		)
		(fp_line
			(start 0.8636 -0.8636)
			(end -0.8636 -0.8636)
			(stroke
				(width 0.1524)
				(type default)
			)
			(layer "F.SilkS")
		)
		(fp_line
			(start 0.8636 0.8636)
			(end 0.8636 -0.8636)
			(stroke
				(width 0.1524)
				(type default)
			)
			(layer "F.SilkS")
		)
		(fp_poly
			(pts
				(xy -0.635 -0.635) (xy -0.635 0.635) (xy 0.635 0.635) (xy 0.635 -0.635)
			)
			(stroke
				(width 0)
				(type default)
			)
			(fill no)
			(layer "F.CrtYd")
		)
		(pad "1" smd rect
			(at 0 0)
			(size 1.27 1.27)
			(layers "F.Cu" "F.Mask" "F.Paste")
			(net "CPLD_GPIO_3")
		)
	)
	(footprint ""
		(layer "F.Cu")
		(at 77.47 26.8732 180)
		(property "Reference" "C110"
			(at 0 0 180)
			(layer "F.SilkS")
			(hide yes)
			(effects
				(font
					(size 1.27 1.27)
				)
			)
		)
		(property "Value" "0.1UF"
			(at -0.091846 0.2921 270)
			(unlocked yes)
			(layer "F.Fab")
			(hide yes)
			(effects
				(font
					(size 0.7874 0.5842)
					(thickness 0.2032)
				)
				(justify left)
			)
		)
		(property "Device Type" "CAPC0073"
			(at -0.091846 0.2921 270)
			(unlocked yes)
			(layer "F.Fab")
			(hide yes)
			(effects
				(font
					(size 0.7874 0.5842)
					(thickness 0.2032)
				)
				(justify left)
			)
		)
		(duplicate_pad_numbers_are_jumpers no)
		(fp_poly
			(pts
				(xy 0.635 1.0668) (xy 0.635 -1.0668) (xy -0.635 -1.0668) (xy -0.635 1.0668)
			)
			(stroke
				(width 0)
				(type default)
			)
			(fill no)
			(layer "F.CrtYd")
		)
		(fp_line
			(start 0.254 0.508)
			(end -0.254 0.508)
			(stroke
				(width 0.0254)
				(type default)
			)
			(layer "F.Fab")
		)
		(fp_line
			(start 0.254 -0.508)
			(end 0.254 0.508)
			(stroke
				(width 0.0254)
				(type default)
			)
			(layer "F.Fab")
		)
		(fp_line
			(start -0.254 0.508)
			(end -0.254 -0.508)
			(stroke
				(width 0.0254)
				(type default)
			)
			(layer "F.Fab")
		)
		(fp_line
			(start -0.254 -0.508)
			(end 0.254 -0.508)
			(stroke
				(width 0.0254)
				(type default)
			)
			(layer "F.Fab")
		)
		(pad "1" smd rect
			(at 0 -0.4191 180)
			(size 0.508 0.5334)
			(layers "F.Cu" "F.Mask" "F.Paste")
			(net "DDR_VTT")
		)
		(pad "2" smd rect
			(at 0 0.4191 180)
			(size 0.508 0.5334)
			(layers "F.Cu" "F.Mask" "F.Paste")
			(net "GND")
		)
		(zone
			(layer "F.Cu")
			(hatch none 0.5)
			(connect_pads
				(clearance 0)
			)
			(min_thickness 0.25)
			(keepout
				(tracks not_allowed)
				(vias allowed)
				(pads allowed)
				(copperpour not_allowed)
				(footprints allowed)
			)
			(placement
				(enabled no)
				(sheetname "")
			)
			(fill
				(thermal_gap 0.5)
				(thermal_bridge_width 0.5)
				(island_removal_mode 0)
			)
			(polygon
				(pts
					(xy 77.4446 26.8986) (xy 77.4446 26.8478) (xy 77.4954 26.8478) (xy 77.4954 26.8986)
				)
			)
		)
	)
	(footprint ""
		(layer "F.Cu")
		(at 80.137 32.576414 180)
		(property "Reference" "R353"
			(at -0.02667 -4.507586 90)
			(unlocked yes)
			(layer "F.SilkS")
			(effects
				(font
					(size 0.7874 0.5842)
					(thickness 0.127)
				)
				(justify left)
			)
		)
		(property "Value" "240"
			(at -0.148158 1.3462 270)
			(unlocked yes)
			(layer "F.Fab")
			(hide yes)
			(effects
				(font
					(size 1.27 0.9652)
					(thickness 0.000001)
				)
				(justify left)
			)
		)
		(property "Device Type" "REST0009"
			(at -0.148158 1.3462 270)
			(unlocked yes)
			(layer "F.Fab")
			(hide yes)
			(effects
				(font
					(size 1.27 0.9652)
					(thickness 0.000001)
				)
				(justify left)
			)
		)
		(duplicate_pad_numbers_are_jumpers no)
		(fp_poly
			(pts
				(xy 0.635 1.0668) (xy 0.635 -1.0668) (xy -0.635 -1.0668) (xy -0.635 1.0668)
			)
			(stroke
				(width 0)
				(type default)
			)
			(fill no)
			(layer "F.CrtYd")
		)
		(fp_line
			(start 0.254 0.508)
			(end -0.254 0.508)
			(stroke
				(width 0.0254)
				(type default)
			)
			(layer "F.Fab")
		)
		(fp_line
			(start 0.254 -0.508)
			(end 0.254 0.508)
			(stroke
				(width 0.0254)
				(type default)
			)
			(layer "F.Fab")
		)
		(fp_line
			(start -0.254 0.508)
			(end -0.254 -0.508)
			(stroke
				(width 0.0254)
				(type default)
			)
			(layer "F.Fab")
		)
		(fp_line
			(start -0.254 -0.508)
			(end 0.254 -0.508)
			(stroke
				(width 0.0254)
				(type default)
			)
			(layer "F.Fab")
		)
		(pad "1" smd rect
			(at 0 -0.4191 180)
			(size 0.508 0.5334)
			(layers "F.Cu" "F.Mask" "F.Paste")
			(net "GND")
		)
		(pad "2" smd rect
			(at 0 0.4191 180)
			(size 0.508 0.5334)
			(layers "F.Cu" "F.Mask" "F.Paste")
			(net "12N3220")
		)
		(zone
			(layer "F.Cu")
			(hatch none 0.5)
			(connect_pads
				(clearance 0)
			)
			(min_thickness 0.25)
			(keepout
				(tracks not_allowed)
				(vias allowed)
				(pads allowed)
				(copperpour not_allowed)
				(footprints allowed)
			)
			(placement
				(enabled no)
				(sheetname "")
			)
			(fill
				(thermal_gap 0.5)
				(thermal_bridge_width 0.5)
				(island_removal_mode 0)
			)
			(polygon
				(pts
					(xy 80.1116 32.601814) (xy 80.1116 32.551014) (xy 80.1624 32.551014) (xy 80.1624 32.601814)
				)
			)
		)
	)
	(footprint ""
		(layer "F.Cu")
		(at 81.153 35.687 180)
		(property "Reference" "R335"
			(at 0 0 180)
			(layer "F.SilkS")
			(hide yes)
			(effects
				(font
					(size 1.27 1.27)
				)
			)
		)
		(property "Value" "0"
			(at -0.148158 1.3462 270)
			(unlocked yes)
			(layer "F.Fab")
			(hide yes)
			(effects
				(font
					(size 1.27 0.9652)
					(thickness 0.000001)
				)
				(justify left)
			)
		)
		(property "Device Type" "REST1111"
			(at -0.148158 1.3462 270)
			(unlocked yes)
			(layer "F.Fab")
			(hide yes)
			(effects
				(font
					(size 1.27 0.9652)
					(thickness 0.000001)
				)
				(justify left)
			)
		)
		(duplicate_pad_numbers_are_jumpers no)
		(fp_poly
			(pts
				(xy 0.635 1.0668) (xy 0.635 -1.0668) (xy -0.635 -1.0668) (xy -0.635 1.0668)
			)
			(stroke
				(width 0)
				(type default)
			)
			(fill no)
			(layer "F.CrtYd")
		)
		(fp_line
			(start 0.254 0.508)
			(end -0.254 0.508)
			(stroke
				(width 0.0254)
				(type default)
			)
			(layer "F.Fab")
		)
		(fp_line
			(start 0.254 -0.508)
			(end 0.254 0.508)
			(stroke
				(width 0.0254)
				(type default)
			)
			(layer "F.Fab")
		)
		(fp_line
			(start -0.254 0.508)
			(end -0.254 -0.508)
			(stroke
				(width 0.0254)
				(type default)
			)
			(layer "F.Fab")
		)
		(fp_line
			(start -0.254 -0.508)
			(end 0.254 -0.508)
			(stroke
				(width 0.0254)
				(type default)
			)
			(layer "F.Fab")
		)
		(pad "1" smd rect
			(at 0 -0.4191 180)
			(size 0.508 0.5334)
			(layers "F.Cu" "F.Mask" "F.Paste")
			(net "11N2191")
		)
		(pad "2" smd rect
			(at 0 0.4191 180)
			(size 0.508 0.5334)
			(layers "F.Cu" "F.Mask" "F.Paste")
			(net "DDR_VDDQ")
		)
		(zone
			(layer "F.Cu")
			(hatch none 0.5)
			(connect_pads
				(clearance 0)
			)
			(min_thickness 0.25)
			(keepout
				(tracks not_allowed)
				(vias allowed)
				(pads allowed)
				(copperpour not_allowed)
				(footprints allowed)
			)
			(placement
				(enabled no)
				(sheetname "")
			)
			(fill
				(thermal_gap 0.5)
				(thermal_bridge_width 0.5)
				(island_removal_mode 0)
			)
			(polygon
				(pts
					(xy 81.1276 35.7124) (xy 81.1276 35.6616) (xy 81.1784 35.6616) (xy 81.1784 35.7124)
				)
			)
		)
	)
	(footprint ""
		(layer "F.Cu")
		(at 20.701 16.8529 180)
		(property "Reference" "C87"
			(at 2.54 -0.44577 0)
			(unlocked yes)
			(layer "F.SilkS")
			(effects
				(font
					(size 0.7874 0.5842)
					(thickness 0.127)
				)
				(justify left)
			)
		)
		(property "Value" "0.1UF"
			(at -0.091846 0.2921 270)
			(unlocked yes)
			(layer "F.Fab")
			(hide yes)
			(effects
				(font
					(size 0.7874 0.5842)
					(thickness 0.2032)
				)
				(justify left)
			)
		)
		(property "Device Type" "CAPC0073"
			(at -0.091846 0.2921 270)
			(unlocked yes)
			(layer "F.Fab")
			(hide yes)
			(effects
				(font
					(size 0.7874 0.5842)
					(thickness 0.2032)
				)
				(justify left)
			)
		)
		(duplicate_pad_numbers_are_jumpers no)
		(fp_poly
			(pts
				(xy 0.635 1.0668) (xy 0.635 -1.0668) (xy -0.635 -1.0668) (xy -0.635 1.0668)
			)
			(stroke
				(width 0)
				(type default)
			)
			(fill no)
			(layer "F.CrtYd")
		)
		(fp_line
			(start 0.254 0.508)
			(end -0.254 0.508)
			(stroke
				(width 0.0254)
				(type default)
			)
			(layer "F.Fab")
		)
		(fp_line
			(start 0.254 -0.508)
			(end 0.254 0.508)
			(stroke
				(width 0.0254)
				(type default)
			)
			(layer "F.Fab")
		)
		(fp_line
			(start -0.254 0.508)
			(end -0.254 -0.508)
			(stroke
				(width 0.0254)
				(type default)
			)
			(layer "F.Fab")
		)
		(fp_line
			(start -0.254 -0.508)
			(end 0.254 -0.508)
			(stroke
				(width 0.0254)
				(type default)
			)
			(layer "F.Fab")
		)
		(pad "1" smd rect
			(at 0 -0.4191 180)
			(size 0.508 0.5334)
			(layers "F.Cu" "F.Mask" "F.Paste")
			(net "VDD_3.3V")
		)
		(pad "2" smd rect
			(at 0 0.4191 180)
			(size 0.508 0.5334)
			(layers "F.Cu" "F.Mask" "F.Paste")
			(net "GND")
		)
		(zone
			(layer "F.Cu")
			(hatch none 0.5)
			(connect_pads
				(clearance 0)
			)
			(min_thickness 0.25)
			(keepout
				(tracks not_allowed)
				(vias allowed)
				(pads allowed)
				(copperpour not_allowed)
				(footprints allowed)
			)
			(placement
				(enabled no)
				(sheetname "")
			)
			(fill
				(thermal_gap 0.5)
				(thermal_bridge_width 0.5)
				(island_removal_mode 0)
			)
			(polygon
				(pts
					(xy 20.6756 16.8783) (xy 20.6756 16.8275) (xy 20.7264 16.8275) (xy 20.7264 16.8783)
				)
			)
		)
	)
	(footprint ""
		(layer "F.Cu")
		(at 76.251003 25.813004)
		(property "Reference" "V_A-DQS4-N"
			(at 0 0 0)
			(layer "F.SilkS")
			(hide yes)
			(effects
				(font
					(size 1.27 1.27)
				)
			)
		)
		(property "Value" ""
			(at 0 0 0)
			(layer "F.Fab")
			(effects
				(font
					(size 1.27 1.27)
				)
			)
		)
		(duplicate_pad_numbers_are_jumpers no)
		(pad "1" thru_hole circle
			(at 0 0)
			(size 0.762 0.762)
			(drill 0.20574)
			(layers "*.Cu" "*.Mask")
			(remove_unused_layers no)
			(net "DDR0_32A_DQS4_N")
			(clearance 0.127)
			(thermal_gap 0.127)
			(padstack
				(mode front_inner_back)
				(layer "Inner"
					(shape circle)
					(size 0.4572 0.4572)
					(clearance 0.1143)
				)
				(layer "B.Cu"
					(shape circle)
					(size 0.4572 0.4572)
					(clearance 0.1143)
				)
			)
		)
	)
	(footprint ""
		(layer "F.Cu")
		(at 27.432 32.639)
		(property "Reference" "R83"
			(at 0 0 0)
			(layer "F.SilkS")
			(hide yes)
			(effects
				(font
					(size 1.27 1.27)
				)
			)
		)
		(property "Value" "4.75K"
			(at -0.148158 1.3462 90)
			(unlocked yes)
			(layer "F.Fab")
			(hide yes)
			(effects
				(font
					(size 1.27 0.9652)
					(thickness 0.000001)
				)
				(justify left)
			)
		)
		(property "Device Type" "REST4024"
			(at -0.148158 1.3462 90)
			(unlocked yes)
			(layer "F.Fab")
			(hide yes)
			(effects
				(font
					(size 1.27 0.9652)
					(thickness 0.000001)
				)
				(justify left)
			)
		)
		(duplicate_pad_numbers_are_jumpers no)
		(fp_poly
			(pts
				(xy 0.635 1.0668) (xy 0.635 -1.0668) (xy -0.635 -1.0668) (xy -0.635 1.0668)
			)
			(stroke
				(width 0)
				(type default)
			)
			(fill no)
			(layer "F.CrtYd")
		)
		(fp_line
			(start -0.254 -0.508)
			(end 0.254 -0.508)
			(stroke
				(width 0.0254)
				(type default)
			)
			(layer "F.Fab")
		)
		(fp_line
			(start -0.254 0.508)
			(end -0.254 -0.508)
			(stroke
				(width 0.0254)
				(type default)
			)
			(layer "F.Fab")
		)
		(fp_line
			(start 0.254 -0.508)
			(end 0.254 0.508)
			(stroke
				(width 0.0254)
				(type default)
			)
			(layer "F.Fab")
		)
		(fp_line
			(start 0.254 0.508)
			(end -0.254 0.508)
			(stroke
				(width 0.0254)
				(type default)
			)
			(layer "F.Fab")
		)
		(pad "1" smd rect
			(at 0 -0.4191)
			(size 0.508 0.5334)
			(layers "F.Cu" "F.Mask" "F.Paste")
			(net "GND")
		)
		(pad "2" smd rect
			(at 0 0.4191)
			(size 0.508 0.5334)
			(layers "F.Cu" "F.Mask" "F.Paste")
			(net "_NFP_CORE_VID0")
		)
		(zone
			(layer "F.Cu")
			(hatch none 0.5)
			(connect_pads
				(clearance 0)
			)
			(min_thickness 0.25)
			(keepout
				(tracks not_allowed)
				(vias allowed)
				(pads allowed)
				(copperpour not_allowed)
				(footprints allowed)
			)
			(placement
				(enabled no)
				(sheetname "")
			)
			(fill
				(thermal_gap 0.5)
				(thermal_bridge_width 0.5)
				(island_removal_mode 0)
			)
			(polygon
				(pts
					(xy 27.4574 32.6136) (xy 27.4574 32.6644) (xy 27.4066 32.6644) (xy 27.4066 32.6136)
				)
			)
		)
	)
)
